(kicad_pcb
	(version 20241229)
	(generator "pcbnew")
	(generator_version "9.0")
	(general
		(thickness 1.6296)
		(legacy_teardrops no)
	)
	(paper "A3")
	(title_block
		(title "Thunderbolt to 10GbE adapter")
		(date "2026-04-21")
		(rev "1.1.0")
		(company "Antmicro Ltd")
		(comment 1 "www.antmicro.com")
		(comment 9 "footprints 133-137 of 703")
	)
	(layers
		(0 "F.Cu" signal)
		(4 "In1.Cu" signal)
		(6 "In2.Cu" signal)
		(8 "In3.Cu" signal)
		(10 "In4.Cu" signal)
		(12 "In5.Cu" signal)
		(14 "In6.Cu" signal)
		(2 "B.Cu" signal)
		(9 "F.Adhes" user "F.Adhesive")
		(11 "B.Adhes" user "B.Adhesive")
		(13 "F.Paste" user)
		(15 "B.Paste" user)
		(5 "F.SilkS" user "F.Silkscreen")
		(7 "B.SilkS" user "B.Silkscreen")
		(1 "F.Mask" user)
		(3 "B.Mask" user)
		(17 "Dwgs.User" user "User.Drawings")
		(19 "Cmts.User" user "User.Comments")
		(21 "Eco1.User" user "User.Eco1")
		(23 "Eco2.User" user "User.Eco2")
		(25 "Edge.Cuts" user)
		(27 "Margin" user)
		(31 "F.CrtYd" user "F.Courtyard")
		(29 "B.CrtYd" user "B.Courtyard")
		(35 "F.Fab" user)
		(33 "B.Fab" user)
	)
	(footprint "antmicro-footprints:C_0603_1608Metric_EIA"
		(layer "F.Cu")
		(at 135.320001 91.25)
		(descr "Capacitor SMD 0603, IPC-7351 Density Level A")
		(tags "Capacitor 0603")
		(property "Reference" "C144"
			(at 36.934999 -9.199999 0)
			(layer "F.SilkS")
			(effects
				(font
					(size 0.7 0.7)
					(thickness 0.15)
				)
			)
		)
		(property "Value" "C_22u_16V_0603"
			(at -1.42757 1.770288 0)
			(layer "F.Fab")
			(effects
				(font
					(size 0.7 0.7)
					(thickness 0.15)
				)
				(justify left bottom)
			)
		)
		(property "Datasheet" "https://product.samsungsem.com/mlcc/CL10A226MO7JZN.do"
			(at 0 0 0)
			(layer "F.Fab")
			(hide yes)
			(effects
				(font
					(size 1.27 1.27)
					(thickness 0.15)
				)
			)
		)
		(property "Description" "SMD Multilayer Ceramic Capacitor"
			(at 0 0 0)
			(layer "F.Fab")
			(hide yes)
			(effects
				(font
					(size 1.27 1.27)
					(thickness 0.15)
				)
			)
		)
		(property "MPN" "CL10A226MO7JZNC"
			(at 0 0 0)
			(unlocked yes)
			(layer "F.Fab")
			(hide yes)
			(effects
				(font
					(size 1 1)
					(thickness 0.15)
				)
			)
		)
		(property "Manufacturer" "Samsung Electro-Mechanics"
			(at 0 0 0)
			(unlocked yes)
			(layer "F.Fab")
			(hide yes)
			(effects
				(font
					(size 1 1)
					(thickness 0.15)
				)
			)
		)
		(property "License" "Apache-2.0"
			(at 0 0 0)
			(unlocked yes)
			(layer "F.Fab")
			(hide yes)
			(effects
				(font
					(size 1 1)
					(thickness 0.15)
				)
			)
		)
		(property "Author" "Antmicro"
			(at 0 0 0)
			(unlocked yes)
			(layer "F.Fab")
			(hide yes)
			(effects
				(font
					(size 1 1)
					(thickness 0.15)
				)
			)
		)
		(property "Val" "22u"
			(at 0 0 0)
			(unlocked yes)
			(layer "F.Fab")
			(hide yes)
			(effects
				(font
					(size 1 1)
					(thickness 0.15)
				)
			)
		)
		(property "Voltage" "16V"
			(at 0 0 0)
			(unlocked yes)
			(layer "F.Fab")
			(hide yes)
			(effects
				(font
					(size 1 1)
					(thickness 0.15)
				)
			)
		)
		(property "Dielectric" ""
			(at 0 0 0)
			(unlocked yes)
			(layer "F.Fab")
			(hide yes)
			(effects
				(font
					(size 1 1)
					(thickness 0.15)
				)
			)
		)
		(sheetname "/X710 DCDC converters/")
		(sheetfile "DCDC_converters_X710.kicad_sch")
		(attr smd)
		(fp_line
			(start -0.15 -0.55)
			(end 0.15 -0.55)
			(stroke
				(width 0.15)
				(type solid)
			)
			(layer "F.SilkS")
		)
		(fp_line
			(start -0.15 0.55)
			(end 0.15 0.55)
			(stroke
				(width 0.15)
				(type solid)
			)
			(layer "F.SilkS")
		)
		(fp_rect
			(start -1.25 -0.65)
			(end 1.25 0.65)
			(stroke
				(width 0.05)
				(type solid)
			)
			(fill no)
			(layer "F.CrtYd")
		)
		(fp_rect
			(start -0.8 -0.45)
			(end 0.8 0.45)
			(stroke
				(width 0.15)
				(type solid)
			)
			(fill no)
			(layer "F.Fab")
		)
		(fp_text user "License: Apache-2.0"
			(at -1.682 5.895 0)
			(layer "F.Fab")
			(effects
				(font
					(size 0.7 0.7)
					(thickness 0.15)
				)
				(justify left bottom)
			)
		)
		(fp_text user "Author: Antmicro"
			(at -1.682 4.894 0)
			(layer "F.Fab")
			(effects
				(font
					(size 0.7 0.7)
					(thickness 0.15)
				)
				(justify left bottom)
			)
		)
		(fp_text user "${REFERENCE}"
			(at -1.682 3.895 0)
			(layer "F.Fab")
			(effects
				(font
					(size 0.7 0.7)
					(thickness 0.15)
				)
				(justify left bottom)
			)
		)
		(pad "1" smd roundrect
			(at -0.7 0)
			(size 0.8 1.1)
			(layers "F.Cu" "F.Mask" "F.Paste")
			(roundrect_rratio 0.2)
			(net 23 "GND")
			(pintype "passive")
		)
		(pad "2" smd roundrect
			(at 0.7 0)
			(size 0.8 1.1)
			(layers "F.Cu" "F.Mask" "F.Paste")
			(roundrect_rratio 0.2)
			(net 334 "/X710 DCDC converters/+3V3_OUT")
			(pintype "passive")
		)
	)
	(footprint "antmicro-footprints:R_0402_1005Metric"
		(layer "F.Cu")
		(at 173.6 72.1 -90)
		(descr "Resistor SMD 0402")
		(tags "resistor SMD 0402")
		(property "Reference" "R200"
			(at -0.9 -0.4 270)
			(layer "F.SilkS")
			(effects
				(font
					(size 0.7 0.7)
					(thickness 0.15)
				)
				(justify left bottom)
			)
		)
		(property "Value" "R_3k3_0402"
			(at -1.011843 1.772047 270)
			(layer "F.Fab")
			(effects
				(font
					(size 0.7 0.7)
					(thickness 0.15)
				)
				(justify left bottom)
			)
		)
		(property "Datasheet" "https://www.bourns.com/docs/product-datasheets/cr.pdf"
			(at 0 0 270)
			(layer "F.Fab")
			(hide yes)
			(effects
				(font
					(size 1.27 1.27)
					(thickness 0.15)
				)
			)
		)
		(property "Description" "SMD Chip Resistor, 3.3 kohm, ± 1%, 63 mW, 0402 [1005 Metric], Thick Film, General Purpose"
			(at 0 0 270)
			(layer "F.Fab")
			(hide yes)
			(effects
				(font
					(size 1.27 1.27)
					(thickness 0.15)
				)
			)
		)
		(property "MPN" "CR0402-FX-3301GLF"
			(at 0 0 270)
			(unlocked yes)
			(layer "F.Fab")
			(hide yes)
			(effects
				(font
					(size 1 1)
					(thickness 0.15)
				)
			)
		)
		(property "Manufacturer" "Bourns"
			(at 0 0 270)
			(unlocked yes)
			(layer "F.Fab")
			(hide yes)
			(effects
				(font
					(size 1 1)
					(thickness 0.15)
				)
			)
		)
		(property "License" "Apache-2.0"
			(at 0 0 270)
			(unlocked yes)
			(layer "F.Fab")
			(hide yes)
			(effects
				(font
					(size 1 1)
					(thickness 0.15)
				)
			)
		)
		(property "Author" "Antmicro"
			(at 0 0 270)
			(unlocked yes)
			(layer "F.Fab")
			(hide yes)
			(effects
				(font
					(size 1 1)
					(thickness 0.15)
				)
			)
		)
		(property "Val" "3k3"
			(at 0 0 270)
			(unlocked yes)
			(layer "F.Fab")
			(hide yes)
			(effects
				(font
					(size 1 1)
					(thickness 0.15)
				)
			)
		)
		(property "Tolerance" "1%"
			(at 0 0 270)
			(unlocked yes)
			(layer "F.Fab")
			(hide yes)
			(effects
				(font
					(size 1 1)
					(thickness 0.15)
				)
			)
		)
		(sheetname "/X710-AT2 10GbE/")
		(sheetfile "x710-at2-10gbe.kicad_sch")
		(attr smd)
		(fp_rect
			(start -0.925 -0.47)
			(end 0.925 0.47)
			(stroke
				(width 0.05)
				(type default)
			)
			(fill no)
			(layer "F.CrtYd")
		)
		(fp_rect
			(start -0.5 -0.25)
			(end 0.5 0.25)
			(stroke
				(width 0.15)
				(type solid)
			)
			(fill no)
			(layer "F.Fab")
		)
		(fp_text user "${REFERENCE}"
			(at -0.95 3.168 270)
			(layer "F.Fab")
			(effects
				(font
					(size 0.7 0.7)
					(thickness 0.15)
				)
				(justify left bottom)
			)
		)
		(fp_text user "License: Apache-2.0"
			(at -0.95 5.169 270)
			(layer "F.Fab")
			(effects
				(font
					(size 0.7 0.7)
					(thickness 0.15)
				)
				(justify left bottom)
			)
		)
		(fp_text user "Author: Antmicro"
			(at -0.95 4.169 270)
			(layer "F.Fab")
			(effects
				(font
					(size 0.7 0.7)
					(thickness 0.15)
				)
				(justify left bottom)
			)
		)
		(pad "1" smd roundrect
			(at -0.48 0 270)
			(size 0.59 0.64)
			(layers "F.Cu" "F.Mask" "F.Paste")
			(roundrect_rratio 0.25)
			(net 100 "/X710-AT2 10GbE/MDC0_SCL0")
			(pintype "passive")
		)
		(pad "2" smd roundrect
			(at 0.48 0 270)
			(size 0.59 0.64)
			(layers "F.Cu" "F.Mask" "F.Paste")
			(roundrect_rratio 0.25)
			(net 7 "+3V3")
			(pintype "passive")
		)
	)
	(footprint "antmicro-footprints:R_0402_1005Metric"
		(layer "F.Cu")
		(at 125.02 89.04 180)
		(descr "Resistor SMD 0402")
		(tags "resistor SMD 0402")
		(property "Reference" "R117"
			(at 1.82 0.509 180)
			(layer "F.SilkS")
			(effects
				(font
					(size 0.7 0.7)
					(thickness 0.15)
				)
				(justify left bottom)
			)
		)
		(property "Value" "R_8k2_0402"
			(at -1.011843 1.772047 180)
			(layer "F.Fab")
			(effects
				(font
					(size 0.7 0.7)
					(thickness 0.15)
				)
				(justify left bottom)
			)
		)
		(property "Datasheet" "https://www.bourns.com/docs/product-datasheets/cr.pdf"
			(at 0 0 180)
			(layer "F.Fab")
			(hide yes)
			(effects
				(font
					(size 1.27 1.27)
					(thickness 0.15)
				)
			)
		)
		(property "Description" "SMD Chip Resistor"
			(at 0 0 180)
			(layer "F.Fab")
			(hide yes)
			(effects
				(font
					(size 1.27 1.27)
					(thickness 0.15)
				)
			)
		)
		(property "MPN" "CR0402-FX-8201GLF"
			(at 0 0 180)
			(unlocked yes)
			(layer "F.Fab")
			(hide yes)
			(effects
				(font
					(size 1 1)
					(thickness 0.15)
				)
			)
		)
		(property "Manufacturer" "Bourns"
			(at 0 0 180)
			(unlocked yes)
			(layer "F.Fab")
			(hide yes)
			(effects
				(font
					(size 1 1)
					(thickness 0.15)
				)
			)
		)
		(property "License" "Apache-2.0"
			(at 0 0 180)
			(unlocked yes)
			(layer "F.Fab")
			(hide yes)
			(effects
				(font
					(size 1 1)
					(thickness 0.15)
				)
			)
		)
		(property "Author" "Antmicro"
			(at 0 0 180)
			(unlocked yes)
			(layer "F.Fab")
			(hide yes)
			(effects
				(font
					(size 1 1)
					(thickness 0.15)
				)
			)
		)
		(property "Val" "8k2"
			(at 0 0 180)
			(unlocked yes)
			(layer "F.Fab")
			(hide yes)
			(effects
				(font
					(size 1 1)
					(thickness 0.15)
				)
			)
		)
		(property "Tolerance" "1%"
			(at 0 0 180)
			(unlocked yes)
			(layer "F.Fab")
			(hide yes)
			(effects
				(font
					(size 1 1)
					(thickness 0.15)
				)
			)
		)
		(sheetname "/X710-AT2 PCIe/")
		(sheetfile "x710-at2-pcie.kicad_sch")
		(attr smd)
		(fp_rect
			(start -0.925 -0.47)
			(end 0.925 0.47)
			(stroke
				(width 0.05)
				(type default)
			)
			(fill no)
			(layer "F.CrtYd")
		)
		(fp_rect
			(start -0.5 -0.25)
			(end 0.5 0.25)
			(stroke
				(width 0.15)
				(type solid)
			)
			(fill no)
			(layer "F.Fab")
		)
		(fp_text user "License: Apache-2.0"
			(at -0.95 5.169 180)
			(layer "F.Fab")
			(effects
				(font
					(size 0.7 0.7)
					(thickness 0.15)
				)
				(justify left bottom)
			)
		)
		(fp_text user "${REFERENCE}"
			(at -0.95 3.168 180)
			(layer "F.Fab")
			(effects
				(font
					(size 0.7 0.7)
					(thickness 0.15)
				)
				(justify left bottom)
			)
		)
		(fp_text user "Author: Antmicro"
			(at -0.95 4.169 180)
			(layer "F.Fab")
			(effects
				(font
					(size 0.7 0.7)
					(thickness 0.15)
				)
				(justify left bottom)
			)
		)
		(pad "1" smd roundrect
			(at -0.48 0 180)
			(size 0.59 0.64)
			(layers "F.Cu" "F.Mask" "F.Paste")
			(roundrect_rratio 0.25)
			(net 11 "/X710-AT2 PCIe/PCIe_JTAG.JTDI")
			(pintype "passive")
		)
		(pad "2" smd roundrect
			(at 0.48 0 180)
			(size 0.59 0.64)
			(layers "F.Cu" "F.Mask" "F.Paste")
			(roundrect_rratio 0.25)
			(net 7 "+3V3")
			(pintype "passive")
		)
	)
	(footprint "antmicro-footprints:C_0402_1005Metric"
		(layer "F.Cu")
		(at 159.249999 109.15)
		(descr "Capacitor SMD 0402")
		(tags "capacitor SMD 0402")
		(property "Reference" "C122"
			(at 12.950004 17.25 0)
			(layer "F.SilkS")
			(effects
				(font
					(size 0.7 0.7)
					(thickness 0.15)
				)
			)
		)
		(property "Value" "C_1u_25V_0402"
			(at -1.022927 2.155213 0)
			(layer "F.Fab")
			(effects
				(font
					(size 0.7 0.7)
					(thickness 0.15)
				)
				(justify left bottom)
			)
		)
		(property "Datasheet" "https://www.murata.com/products/productdetail?partno=GRM155R61E105KE11%23"
			(at 0 0 0)
			(layer "F.Fab")
			(hide yes)
			(effects
				(font
					(size 1.27 1.27)
					(thickness 0.15)
				)
			)
		)
		(property "Description" "SMD Multilayer Ceramic Capacitor, 1 µF, 25 V, 0402 [1005 Metric], ± 10%, X5R, GRM Series"
			(at 0 0 0)
			(layer "F.Fab")
			(hide yes)
			(effects
				(font
					(size 1.27 1.27)
					(thickness 0.15)
				)
			)
		)
		(property "MPN" "GRM155R61E105KE11J"
			(at 0 0 0)
			(unlocked yes)
			(layer "F.Fab")
			(hide yes)
			(effects
				(font
					(size 1 1)
					(thickness 0.15)
				)
			)
		)
		(property "Manufacturer" "Murata"
			(at 0 0 0)
			(unlocked yes)
			(layer "F.Fab")
			(hide yes)
			(effects
				(font
					(size 1 1)
					(thickness 0.15)
				)
			)
		)
		(property "License" "Apache-2.0"
			(at 0 0 0)
			(unlocked yes)
			(layer "F.Fab")
			(hide yes)
			(effects
				(font
					(size 1 1)
					(thickness 0.15)
				)
			)
		)
		(property "Author" "Antmicro"
			(at 0 0 0)
			(unlocked yes)
			(layer "F.Fab")
			(hide yes)
			(effects
				(font
					(size 1 1)
					(thickness 0.15)
				)
			)
		)
		(property "Val" "1u"
			(at 0 0 0)
			(unlocked yes)
			(layer "F.Fab")
			(hide yes)
			(effects
				(font
					(size 1 1)
					(thickness 0.15)
				)
			)
		)
		(property "Voltage" "25V"
			(at 0 0 0)
			(unlocked yes)
			(layer "F.Fab")
			(hide yes)
			(effects
				(font
					(size 1 1)
					(thickness 0.15)
				)
			)
		)
		(property "Dielectric" "X5R"
			(at 0 0 0)
			(unlocked yes)
			(layer "F.Fab")
			(hide yes)
			(effects
				(font
					(size 1 1)
					(thickness 0.15)
				)
			)
		)
		(sheetname "/X710 DCDC converters/")
		(sheetfile "DCDC_converters_X710.kicad_sch")
		(attr smd)
		(fp_rect
			(start -0.925 -0.47)
			(end 0.925 0.47)
			(stroke
				(width 0.05)
				(type default)
			)
			(fill no)
			(layer "F.CrtYd")
		)
		(fp_line
			(start -0.494 -0.25)
			(end 0.504 -0.25)
			(stroke
				(width 0.15)
				(type solid)
			)
			(layer "F.Fab")
		)
		(fp_line
			(start -0.494 0.248)
			(end -0.494 -0.25)
			(stroke
				(width 0.15)
				(type solid)
			)
			(layer "F.Fab")
		)
		(fp_line
			(start 0.504 -0.25)
			(end 0.504 0.248)
			(stroke
				(width 0.15)
				(type solid)
			)
			(layer "F.Fab")
		)
		(fp_line
			(start 0.504 0.248)
			(end -0.494 0.248)
			(stroke
				(width 0.15)
				(type solid)
			)
			(layer "F.Fab")
		)
		(fp_text user "License: Apache-2.0"
			(at -0.939 5.799 0)
			(layer "F.Fab")
			(effects
				(font
					(size 0.7 0.7)
					(thickness 0.15)
				)
				(justify left bottom)
			)
		)
		(fp_text user "Author: Antmicro"
			(at -0.939 3.399 0)
			(layer "F.Fab")
			(effects
				(font
					(size 0.7 0.7)
					(thickness 0.15)
				)
				(justify left bottom)
			)
		)
		(fp_text user "${REFERENCE}"
			(at -0.939 4.599 0)
			(layer "F.Fab")
			(effects
				(font
					(size 0.7 0.7)
					(thickness 0.15)
				)
				(justify left bottom)
			)
		)
		(pad "1" smd roundrect
			(at -0.48 0)
			(size 0.59 0.64)
			(layers "F.Cu" "F.Mask" "F.Paste")
			(roundrect_rratio 0.25)
			(net 23 "GND")
			(pintype "passive")
		)
		(pad "2" smd roundrect
			(at 0.48 0)
			(size 0.59 0.64)
			(layers "F.Cu" "F.Mask" "F.Paste")
			(roundrect_rratio 0.25)
			(net 109 "/X710 DCDC converters/1V0_VCC")
			(pintype "passive")
		)
	)
	(footprint "antmicro-footprints:R_0402_1005Metric"
		(layer "F.Cu")
		(at 142.31 96.674999 180)
		(descr "Resistor SMD 0402")
		(tags "resistor SMD 0402")
		(property "Reference" "R183"
			(at -2.190001 -0.025001 180)
			(layer "F.SilkS")
			(effects
				(font
					(size 0.7 0.7)
					(thickness 0.15)
				)
			)
		)
		(property "Value" "R_8k2_0402"
			(at -1.011843 1.772047 180)
			(layer "F.Fab")
			(effects
				(font
					(size 0.7 0.7)
					(thickness 0.15)
				)
				(justify left bottom)
			)
		)
		(property "Datasheet" "https://www.bourns.com/docs/product-datasheets/cr.pdf"
			(at 0 0 180)
			(layer "F.Fab")
			(hide yes)
			(effects
				(font
					(size 1.27 1.27)
					(thickness 0.15)
				)
			)
		)
		(property "Description" "SMD Chip Resistor"
			(at 0 0 180)
			(layer "F.Fab")
			(hide yes)
			(effects
				(font
					(size 1.27 1.27)
					(thickness 0.15)
				)
			)
		)
		(property "MPN" "CR0402-FX-8201GLF"
			(at 0 0 180)
			(unlocked yes)
			(layer "F.Fab")
			(hide yes)
			(effects
				(font
					(size 1 1)
					(thickness 0.15)
				)
			)
		)
		(property "Manufacturer" "Bourns"
			(at 0 0 180)
			(unlocked yes)
			(layer "F.Fab")
			(hide yes)
			(effects
				(font
					(size 1 1)
					(thickness 0.15)
				)
			)
		)
		(property "License" "Apache-2.0"
			(at 0 0 180)
			(unlocked yes)
			(layer "F.Fab")
			(hide yes)
			(effects
				(font
					(size 1 1)
					(thickness 0.15)
				)
			)
		)
		(property "Author" "Antmicro"
			(at 0 0 180)
			(unlocked yes)
			(layer "F.Fab")
			(hide yes)
			(effects
				(font
					(size 1 1)
					(thickness 0.15)
				)
			)
		)
		(property "Val" "8k2"
			(at 0 0 180)
			(unlocked yes)
			(layer "F.Fab")
			(hide yes)
			(effects
				(font
					(size 1 1)
					(thickness 0.15)
				)
			)
		)
		(property "Tolerance" "1%"
			(at 0 0 180)
			(unlocked yes)
			(layer "F.Fab")
			(hide yes)
			(effects
				(font
					(size 1 1)
					(thickness 0.15)
				)
			)
		)
		(sheetname "/X710-AT2 Misc/")
		(sheetfile "x710-at2-mics.kicad_sch")
		(attr smd)
		(fp_rect
			(start -0.925 -0.47)
			(end 0.925 0.47)
			(stroke
				(width 0.05)
				(type default)
			)
			(fill no)
			(layer "F.CrtYd")
		)
		(fp_rect
			(start -0.5 -0.25)
			(end 0.5 0.25)
			(stroke
				(width 0.15)
				(type solid)
			)
			(fill no)
			(layer "F.Fab")
		)
		(fp_text user "License: Apache-2.0"
			(at -0.95 5.169 180)
			(layer "F.Fab")
			(effects
				(font
					(size 0.7 0.7)
					(thickness 0.15)
				)
				(justify left bottom)
			)
		)
		(fp_text user "Author: Antmicro"
			(at -0.95 4.169 180)
			(layer "F.Fab")
			(effects
				(font
					(size 0.7 0.7)
					(thickness 0.15)
				)
				(justify left bottom)
			)
		)
		(fp_text user "${REFERENCE}"
			(at -0.95 3.168 180)
			(layer "F.Fab")
			(effects
				(font
					(size 0.7 0.7)
					(thickness 0.15)
				)
				(justify left bottom)
			)
		)
		(pad "1" smd roundrect
			(at -0.48 0 180)
			(size 0.59 0.64)
			(layers "F.Cu" "F.Mask" "F.Paste")
			(roundrect_rratio 0.25)
			(net 23 "GND")
			(pintype "passive")
		)
		(pad "2" smd roundrect
			(at 0.48 0 180)
			(size 0.59 0.64)
			(layers "F.Cu" "F.Mask" "F.Paste")
			(roundrect_rratio 0.25)
			(net 353 "/X710 flash memory/FLASH.CLK")
			(pintype "passive")
		)
	)
)
